# S9S_MB_2U (Grand Teton) — schematic netlist excerpt (pin names and nets, part order shuffled) for the footprints in the layout excerpt that follows; sources: Cadence DE-HDL packaged netlist, KiCad conversion of 03242023_DA0F0TMBIJ0_F0T_Motherboard_J_brd_V01_OCP.brd

R3113  Q_RES  33.2 1% CHIP  pkg 0402LF  page 245 : A = SMB_FAN_3V3AUX_SCL ; B = SMB_FAN_3V3AUX_R_SCL
R2492  Q_RES  1K 1% CHIP  pkg 0402LF  page 115 : A = PWRGD_FAIL_CPU0_EF ; B = PWRGD_FAIL_CPU0_EF_R1

(kicad_pcb
	(version 20260206)
	(generator "pcbnew")
	(generator_version "10.0")
	(general
		(thickness 1.6)
		(legacy_teardrops no)
	)
	(paper "A4")
	(title_block
		(title "03242023_DA0F0TMBIJ0_F0T_Motherboard_J_brd_V01_OCP.brd")
		(comment 1 "Grand Teton / footprints 4752-4753 of 6105")
	)
	(layers
		(0 "F.Cu" signal "TOP")
		(4 "In1.Cu" signal "GND")
		(6 "In2.Cu" signal "IN1")
		(8 "In3.Cu" signal "GND1")
		(10 "In4.Cu" signal "IN2")
		(12 "In5.Cu" signal "GND2")
		(14 "In6.Cu" signal "IN3")
		(16 "In7.Cu" signal "GND3")
		(18 "In8.Cu" signal "VCC")
		(20 "In9.Cu" signal "VCC1")
		(22 "In10.Cu" signal "GND4")
		(24 "In11.Cu" signal "IN4")
		(26 "In12.Cu" signal "GND5")
		(28 "In13.Cu" signal "IN5")
		(30 "In14.Cu" signal "GND6")
		(32 "In15.Cu" signal "IN6")
		(34 "In16.Cu" signal "GND7")
		(2 "B.Cu" signal "BOTTOM")
		(9 "F.Adhes" user "F.Adhesive")
		(11 "B.Adhes" user "B.Adhesive")
		(13 "F.Paste" user "Package Geometry/Pastemask Top")
		(15 "B.Paste" user "Package Geometry/Pastemask Bottom")
		(5 "F.SilkS" user "Ref Des/Silkscreen Top")
		(7 "B.SilkS" user "Ref Des/Silkscreen Bottom")
		(1 "F.Mask" user "Board Geometry/Soldermask Top")
		(3 "B.Mask" user "Board Geometry/Soldermask Bottom")
		(17 "Dwgs.User" user "User.Drawings")
		(19 "Cmts.User" user "User.Comments")
		(21 "Eco1.User" user "User.Eco1")
		(23 "Eco2.User" user "User.Eco2")
		(25 "Edge.Cuts" user "Board Geometry/Outline")
		(27 "Margin" user)
		(31 "F.CrtYd" user "Package Geometry/Place Bound Top")
		(29 "B.CrtYd" user "Package Geometry/Place Bound Bottom")
		(35 "F.Fab" user "Ref Des/Assembly Top")
		(33 "B.Fab" user "Ref Des/Assembly Bottom")
	)
	(footprint ""
		(layer "B.Cu")
		(at 433.273962 -317.102998 90)
		(property "Reference" "R2492"
			(at 0 0 90)
			(layer "B.SilkS")
			(hide yes)
			(effects
				(font
					(size 1.27 1.27)
				)
				(justify mirror)
			)
		)
		(property "Value" ""
			(at 0 0 90)
			(layer "B.Fab")
			(effects
				(font
					(size 1.27 1.27)
				)
				(justify mirror)
			)
		)
		(duplicate_pad_numbers_are_jumpers no)
		(fp_line
			(start 0.7874 -0.4064)
			(end -0.7874 -0.4064)
			(stroke
				(width 0.1524)
				(type default)
			)
			(layer "B.SilkS")
		)
		(fp_line
			(start -0.7874 -0.4064)
			(end -0.7874 0.4064)
			(stroke
				(width 0.1524)
				(type default)
			)
			(layer "B.SilkS")
		)
		(fp_line
			(start 0.7874 0.4064)
			(end 0.7874 -0.4064)
			(stroke
				(width 0.1524)
				(type default)
			)
			(layer "B.SilkS")
		)
		(fp_line
			(start -0.7874 0.4064)
			(end 0.7874 0.4064)
			(stroke
				(width 0.1524)
				(type default)
			)
			(layer "B.SilkS")
		)
		(fp_line
			(start 0.67945 -0.305054)
			(end 0.12065 -0.305054)
			(stroke
				(width 0.1)
				(type default)
			)
			(layer "B.Fab")
		)
		(fp_line
			(start 0.12065 -0.305054)
			(end 0.12065 -0.2794)
			(stroke
				(width 0.1)
				(type default)
			)
			(layer "B.Fab")
		)
		(fp_line
			(start -0.12065 -0.3048)
			(end -0.67945 -0.3048)
			(stroke
				(width 0.1)
				(type default)
			)
			(layer "B.Fab")
		)
		(fp_line
			(start -0.67945 -0.3048)
			(end -0.67945 0.3048)
			(stroke
				(width 0.1)
				(type default)
			)
			(layer "B.Fab")
		)
		(fp_line
			(start 0.12065 -0.2794)
			(end -0.12065 -0.2794)
			(stroke
				(width 0.1)
				(type default)
			)
			(layer "B.Fab")
		)
		(fp_line
			(start -0.12065 -0.2794)
			(end -0.12065 -0.3048)
			(stroke
				(width 0.1)
				(type default)
			)
			(layer "B.Fab")
		)
		(fp_line
			(start 0.12065 0.2794)
			(end 0.12065 0.3048)
			(stroke
				(width 0.1)
				(type default)
			)
			(layer "B.Fab")
		)
		(fp_line
			(start -0.120396 0.2794)
			(end 0.12065 0.2794)
			(stroke
				(width 0.1)
				(type default)
			)
			(layer "B.Fab")
		)
		(fp_line
			(start 0.67945 0.3048)
			(end 0.67945 -0.305054)
			(stroke
				(width 0.1)
				(type default)
			)
			(layer "B.Fab")
		)
		(fp_line
			(start 0.12065 0.3048)
			(end 0.67945 0.3048)
			(stroke
				(width 0.1)
				(type default)
			)
			(layer "B.Fab")
		)
		(fp_line
			(start -0.120396 0.3048)
			(end -0.120396 0.2794)
			(stroke
				(width 0.1)
				(type default)
			)
			(layer "B.Fab")
		)
		(fp_line
			(start -0.67945 0.3048)
			(end -0.120396 0.3048)
			(stroke
				(width 0.1)
				(type default)
			)
			(layer "B.Fab")
		)
		(pad "1" smd circle
			(at 0.40005 0 270)
			(size 0 0)
			(layers "B.Cu" "B.Mask" "B.Paste")
			(net "PWRGD_FAIL_CPU0_EF")
		)
		(pad "2" smd circle
			(at -0.40005 0 270)
			(size 0 0)
			(layers "B.Cu" "B.Mask" "B.Paste")
			(net "PWRGD_FAIL_CPU0_EF_R1")
		)
	)
	(footprint ""
		(layer "B.Cu")
		(at 160.28924 -12.774168 90)
		(property "Reference" "R3113"
			(at 0 0 90)
			(layer "B.SilkS")
			(hide yes)
			(effects
				(font
					(size 1.27 1.27)
				)
				(justify mirror)
			)
		)
		(property "Value" ""
			(at 0 0 90)
			(layer "B.Fab")
			(effects
				(font
					(size 1.27 1.27)
				)
				(justify mirror)
			)
		)
		(duplicate_pad_numbers_are_jumpers no)
		(fp_line
			(start 0.7874 -0.4064)
			(end -0.7874 -0.4064)
			(stroke
				(width 0.1524)
				(type default)
			)
			(layer "B.SilkS")
		)
		(fp_line
			(start -0.7874 -0.4064)
			(end -0.7874 0.4064)
			(stroke
				(width 0.1524)
				(type default)
			)
			(layer "B.SilkS")
		)
		(fp_line
			(start 0.7874 0.4064)
			(end 0.7874 -0.4064)
			(stroke
				(width 0.1524)
				(type default)
			)
			(layer "B.SilkS")
		)
		(fp_line
			(start -0.7874 0.4064)
			(end 0.7874 0.4064)
			(stroke
				(width 0.1524)
				(type default)
			)
			(layer "B.SilkS")
		)
		(fp_line
			(start 0.67945 -0.305054)
			(end 0.12065 -0.305054)
			(stroke
				(width 0.1)
				(type default)
			)
			(layer "B.Fab")
		)
		(fp_line
			(start 0.12065 -0.305054)
			(end 0.12065 -0.2794)
			(stroke
				(width 0.1)
				(type default)
			)
			(layer "B.Fab")
		)
		(fp_line
			(start -0.12065 -0.3048)
			(end -0.67945 -0.3048)
			(stroke
				(width 0.1)
				(type default)
			)
			(layer "B.Fab")
		)
		(fp_line
			(start -0.67945 -0.3048)
			(end -0.67945 0.3048)
			(stroke
				(width 0.1)
				(type default)
			)
			(layer "B.Fab")
		)
		(fp_line
			(start 0.12065 -0.2794)
			(end -0.12065 -0.2794)
			(stroke
				(width 0.1)
				(type default)
			)
			(layer "B.Fab")
		)
		(fp_line
			(start -0.12065 -0.2794)
			(end -0.12065 -0.3048)
			(stroke
				(width 0.1)
				(type default)
			)
			(layer "B.Fab")
		)
		(fp_line
			(start 0.12065 0.2794)
			(end 0.12065 0.3048)
			(stroke
				(width 0.1)
				(type default)
			)
			(layer "B.Fab")
		)
		(fp_line
			(start -0.120396 0.2794)
			(end 0.12065 0.2794)
			(stroke
				(width 0.1)
				(type default)
			)
			(layer "B.Fab")
		)
		(fp_line
			(start 0.67945 0.3048)
			(end 0.67945 -0.305054)
			(stroke
				(width 0.1)
				(type default)
			)
			(layer "B.Fab")
		)
		(fp_line
			(start 0.12065 0.3048)
			(end 0.67945 0.3048)
			(stroke
				(width 0.1)
				(type default)
			)
			(layer "B.Fab")
		)
		(fp_line
			(start -0.120396 0.3048)
			(end -0.120396 0.2794)
			(stroke
				(width 0.1)
				(type default)
			)
			(layer "B.Fab")
		)
		(fp_line
			(start -0.67945 0.3048)
			(end -0.120396 0.3048)
			(stroke
				(width 0.1)
				(type default)
			)
			(layer "B.Fab")
		)
		(pad "1" smd circle
			(at 0.40005 0 270)
			(size 0 0)
			(layers "B.Cu" "B.Mask" "B.Paste")
			(net "SMB_FAN_3V3AUX_SCL")
		)
		(pad "2" smd circle
			(at -0.40005 0 270)
			(size 0 0)
			(layers "B.Cu" "B.Mask" "B.Paste")
			(net "SMB_FAN_3V3AUX_R_SCL")
		)
	)
)
